# T6G (Grand Teton) — schematic netlist excerpt (pin names and nets, part order shuffled) for the footprints in the layout excerpt that follows; sources: Cadence DE-HDL packaged netlist, KiCad conversion of 04192023_DAF0TMB3IC0_F0TG_MB_C_brd_V02_OCP.brd

R984  Q_RES  4.7K 5% CHIP  pkg 0201LF  page 276 : A = TEST1_RT_CPU0_P0 ; B = GND
R296  Q_RES  1K 1% CHIP  pkg 0402LF  page 91 : A = PWRGD_CHF_CPU0_DIMM ; B = PWRGD_CHAF_CPU0
R4809  Q_RES  0 5% CHIP  pkg 0402LF  page 150 : A = TP_CHASI ; B = GND

(kicad_pcb
	(version 20260206)
	(generator "pcbnew")
	(generator_version "10.0")
	(general
		(thickness 1.6)
		(legacy_teardrops no)
	)
	(paper "A4")
	(title_block
		(title "04192023_DAF0TMB3IC0_F0TG_MB_C_brd_V02_OCP.brd")
		(comment 1 "Grand Teton / footprints 5268-5270 of 8354")
	)
	(layers
		(0 "F.Cu" signal "TOP")
		(4 "In1.Cu" signal "GND")
		(6 "In2.Cu" signal "IN1")
		(8 "In3.Cu" signal "GND1")
		(10 "In4.Cu" signal "IN2")
		(12 "In5.Cu" signal "GND2")
		(14 "In6.Cu" signal "IN3")
		(16 "In7.Cu" signal "GND3")
		(18 "In8.Cu" signal "VCC")
		(20 "In9.Cu" signal "VCC1")
		(22 "In10.Cu" signal "GND4")
		(24 "In11.Cu" signal "IN4")
		(26 "In12.Cu" signal "GND5")
		(28 "In13.Cu" signal "IN5")
		(30 "In14.Cu" signal "GND6")
		(32 "In15.Cu" signal "IN6")
		(34 "In16.Cu" signal "GND7")
		(2 "B.Cu" signal "BOTTOM")
		(9 "F.Adhes" user "F.Adhesive")
		(11 "B.Adhes" user "B.Adhesive")
		(13 "F.Paste" user "Package Geometry/Pastemask Top")
		(15 "B.Paste" user "Package Geometry/Pastemask Bottom")
		(5 "F.SilkS" user "Ref Des/Silkscreen Top")
		(7 "B.SilkS" user "Ref Des/Silkscreen Bottom")
		(1 "F.Mask" user "Board Geometry/Soldermask Top")
		(3 "B.Mask" user "Board Geometry/Soldermask Bottom")
		(17 "Dwgs.User" user "User.Drawings")
		(19 "Cmts.User" user "User.Comments")
		(21 "Eco1.User" user "User.Eco1")
		(23 "Eco2.User" user "User.Eco2")
		(25 "Edge.Cuts" user "Board Geometry/Outline")
		(27 "Margin" user)
		(31 "F.CrtYd" user "Package Geometry/Place Bound Top")
		(29 "B.CrtYd" user "Package Geometry/Place Bound Bottom")
		(35 "F.Fab" user "Ref Des/Assembly Top")
		(33 "B.Fab" user "Ref Des/Assembly Bottom")
	)
	(footprint ""
		(layer "B.Cu")
		(at 265.506454 -190.82131 180)
		(property "Reference" "R296"
			(at 0 0 0)
			(layer "B.SilkS")
			(hide yes)
			(effects
				(font
					(size 1.27 1.27)
				)
				(justify mirror)
			)
		)
		(property "Value" ""
			(at 0 0 0)
			(layer "B.Fab")
			(effects
				(font
					(size 1.27 1.27)
				)
				(justify mirror)
			)
		)
		(duplicate_pad_numbers_are_jumpers no)
		(fp_line
			(start 0.7874 0.4064)
			(end 0.7874 -0.4064)
			(stroke
				(width 0.1524)
				(type default)
			)
			(layer "B.SilkS")
		)
		(fp_line
			(start 0.7874 -0.4064)
			(end -0.7874 -0.4064)
			(stroke
				(width 0.1524)
				(type default)
			)
			(layer "B.SilkS")
		)
		(fp_line
			(start -0.7874 0.4064)
			(end 0.7874 0.4064)
			(stroke
				(width 0.1524)
				(type default)
			)
			(layer "B.SilkS")
		)
		(fp_line
			(start -0.7874 -0.4064)
			(end -0.7874 0.4064)
			(stroke
				(width 0.1524)
				(type default)
			)
			(layer "B.SilkS")
		)
		(fp_line
			(start 0.67945 0.3048)
			(end 0.67945 -0.305054)
			(stroke
				(width 0.1)
				(type default)
			)
			(layer "B.Fab")
		)
		(fp_line
			(start 0.67945 -0.305054)
			(end 0.12065 -0.305054)
			(stroke
				(width 0.1)
				(type default)
			)
			(layer "B.Fab")
		)
		(fp_line
			(start 0.12065 0.3048)
			(end 0.67945 0.3048)
			(stroke
				(width 0.1)
				(type default)
			)
			(layer "B.Fab")
		)
		(fp_line
			(start 0.12065 0.2794)
			(end 0.12065 0.3048)
			(stroke
				(width 0.1)
				(type default)
			)
			(layer "B.Fab")
		)
		(fp_line
			(start 0.12065 -0.2794)
			(end -0.12065 -0.2794)
			(stroke
				(width 0.1)
				(type default)
			)
			(layer "B.Fab")
		)
		(fp_line
			(start 0.12065 -0.305054)
			(end 0.12065 -0.2794)
			(stroke
				(width 0.1)
				(type default)
			)
			(layer "B.Fab")
		)
		(fp_line
			(start -0.120396 0.3048)
			(end -0.120396 0.2794)
			(stroke
				(width 0.1)
				(type default)
			)
			(layer "B.Fab")
		)
		(fp_line
			(start -0.120396 0.2794)
			(end 0.12065 0.2794)
			(stroke
				(width 0.1)
				(type default)
			)
			(layer "B.Fab")
		)
		(fp_line
			(start -0.12065 -0.2794)
			(end -0.12065 -0.3048)
			(stroke
				(width 0.1)
				(type default)
			)
			(layer "B.Fab")
		)
		(fp_line
			(start -0.12065 -0.3048)
			(end -0.67945 -0.3048)
			(stroke
				(width 0.1)
				(type default)
			)
			(layer "B.Fab")
		)
		(fp_line
			(start -0.67945 0.3048)
			(end -0.120396 0.3048)
			(stroke
				(width 0.1)
				(type default)
			)
			(layer "B.Fab")
		)
		(fp_line
			(start -0.67945 -0.3048)
			(end -0.67945 0.3048)
			(stroke
				(width 0.1)
				(type default)
			)
			(layer "B.Fab")
		)
		(pad "1" smd circle
			(at 0.40005 0)
			(size 0 0)
			(layers "B.Cu" "B.Mask" "B.Paste")
			(net "PWRGD_CHF_CPU0_DIMM")
		)
		(pad "2" smd circle
			(at -0.40005 0)
			(size 0 0)
			(layers "B.Cu" "B.Mask" "B.Paste")
			(net "PWRGD_CHAF_CPU0")
		)
	)
	(footprint ""
		(layer "B.Cu")
		(at 299.265594 -392.66876 180)
		(property "Reference" "R984"
			(at 0 0 0)
			(layer "B.SilkS")
			(hide yes)
			(effects
				(font
					(size 1.27 1.27)
				)
				(justify mirror)
			)
		)
		(property "Value" ""
			(at 0 0 0)
			(layer "B.Fab")
			(effects
				(font
					(size 1.27 1.27)
				)
				(justify mirror)
			)
		)
		(duplicate_pad_numbers_are_jumpers no)
		(fp_line
			(start 0.32512 0.175006)
			(end 0.32512 -0.175006)
			(stroke
				(width 0.1)
				(type default)
			)
			(layer "B.Fab")
		)
		(fp_line
			(start 0.32512 -0.175006)
			(end -0.32512 -0.175006)
			(stroke
				(width 0.1)
				(type default)
			)
			(layer "B.Fab")
		)
		(fp_line
			(start -0.32512 0.175006)
			(end 0.32512 0.175006)
			(stroke
				(width 0.1)
				(type default)
			)
			(layer "B.Fab")
		)
		(fp_line
			(start -0.32512 -0.175006)
			(end -0.32512 0.175006)
			(stroke
				(width 0.1)
				(type default)
			)
			(layer "B.Fab")
		)
		(pad "1" smd rect
			(at 0.2667 0)
			(size 0.3048 0.381)
			(layers "B.Cu" "B.Mask" "B.Paste")
			(net "TEST1_RT_CPU0_P0")
		)
		(pad "2" smd rect
			(at -0.2667 0 180)
			(size 0.3048 0.381)
			(layers "B.Cu" "B.Mask" "B.Paste")
			(net "GND")
		)
	)
	(footprint ""
		(layer "B.Cu")
		(at 139.34694 -13.52169 -90)
		(property "Reference" "R4809"
			(at 0 0 90)
			(layer "B.SilkS")
			(hide yes)
			(effects
				(font
					(size 1.27 1.27)
				)
				(justify mirror)
			)
		)
		(property "Value" ""
			(at 0 0 90)
			(layer "B.Fab")
			(effects
				(font
					(size 1.27 1.27)
				)
				(justify mirror)
			)
		)
		(duplicate_pad_numbers_are_jumpers no)
		(fp_line
			(start -0.7874 0.4064)
			(end 0.7874 0.4064)
			(stroke
				(width 0.1524)
				(type default)
			)
			(layer "B.SilkS")
		)
		(fp_line
			(start 0.7874 0.4064)
			(end 0.7874 -0.4064)
			(stroke
				(width 0.1524)
				(type default)
			)
			(layer "B.SilkS")
		)
		(fp_line
			(start -0.7874 -0.4064)
			(end -0.7874 0.4064)
			(stroke
				(width 0.1524)
				(type default)
			)
			(layer "B.SilkS")
		)
		(fp_line
			(start 0.7874 -0.4064)
			(end -0.7874 -0.4064)
			(stroke
				(width 0.1524)
				(type default)
			)
			(layer "B.SilkS")
		)
		(fp_line
			(start -0.67945 0.3048)
			(end -0.120396 0.3048)
			(stroke
				(width 0.1)
				(type default)
			)
			(layer "B.Fab")
		)
		(fp_line
			(start -0.120396 0.3048)
			(end -0.120396 0.2794)
			(stroke
				(width 0.1)
				(type default)
			)
			(layer "B.Fab")
		)
		(fp_line
			(start 0.12065 0.3048)
			(end 0.67945 0.3048)
			(stroke
				(width 0.1)
				(type default)
			)
			(layer "B.Fab")
		)
		(fp_line
			(start 0.67945 0.3048)
			(end 0.67945 -0.305054)
			(stroke
				(width 0.1)
				(type default)
			)
			(layer "B.Fab")
		)
		(fp_line
			(start -0.120396 0.2794)
			(end 0.12065 0.2794)
			(stroke
				(width 0.1)
				(type default)
			)
			(layer "B.Fab")
		)
		(fp_line
			(start 0.12065 0.2794)
			(end 0.12065 0.3048)
			(stroke
				(width 0.1)
				(type default)
			)
			(layer "B.Fab")
		)
		(fp_line
			(start -0.12065 -0.2794)
			(end -0.12065 -0.3048)
			(stroke
				(width 0.1)
				(type default)
			)
			(layer "B.Fab")
		)
		(fp_line
			(start 0.12065 -0.2794)
			(end -0.12065 -0.2794)
			(stroke
				(width 0.1)
				(type default)
			)
			(layer "B.Fab")
		)
		(fp_line
			(start -0.67945 -0.3048)
			(end -0.67945 0.3048)
			(stroke
				(width 0.1)
				(type default)
			)
			(layer "B.Fab")
		)
		(fp_line
			(start -0.12065 -0.3048)
			(end -0.67945 -0.3048)
			(stroke
				(width 0.1)
				(type default)
			)
			(layer "B.Fab")
		)
		(fp_line
			(start 0.12065 -0.305054)
			(end 0.12065 -0.2794)
			(stroke
				(width 0.1)
				(type default)
			)
			(layer "B.Fab")
		)
		(fp_line
			(start 0.67945 -0.305054)
			(end 0.12065 -0.305054)
			(stroke
				(width 0.1)
				(type default)
			)
			(layer "B.Fab")
		)
		(pad "1" smd circle
			(at 0.40005 0 90)
			(size 0 0)
			(layers "B.Cu" "B.Mask" "B.Paste")
			(net "TP_CHASI")
		)
		(pad "2" smd circle
			(at -0.40005 0 90)
			(size 0 0)
			(layers "B.Cu" "B.Mask" "B.Paste")
			(net "GND")
		)
	)
)
